# BASEBOARD_FAB2 (Tioga Pass) — schematic netlist excerpt (pin names and nets, part order shuffled) for the footprints in the layout excerpt that follows; sources: Cadence DE-HDL packaged netlist, KiCad conversion of Wiwynn_Tioga_Pass_MB.brd

EU4D4  PXE1610B  IC  pkg QFN  page 201
  BPWM1  = VR_PVSA_CPU0_PWM
  APWM6  = NC
  APWM5  = VR_PVCCIN_CPU0_PWM5
  APWM4  = VR_PVCCIN_CPU0_PWM4
  APWM3  = VR_PVCCIN_CPU0_PWM3
  APWM2  = VR_PVCCIN_CPU0_PWM2
  APWM1  = VR_PVCCIN_CPU0_PWM1
  SDA  = SMB_VR_STBY_LVC3_SDA
  SCL  = SMB_VR_STBY_LVC3_SCL
  RESET_N  = NC
  AVRRDY  = VR_VRRDY_PVCCIN_CPU0
  AVREN  = VR_PVCCIN_CPU0_VREN
  VRHOT_N  = IRQ_PVCCIN_CPU0_VRHOT_LVC3_R_N
  PINALRT_N  = FM_PVCCIN_CPU0_PWR_IN_ALERT_N
  MP0  = PWRGD_PVSA_CPU0_R
  MP1  = NC
  VCLK  = SVID_VCLK_PVCCIN_CPU0
  VDIO  = SVID_VDIO_PVCCIN_CPU0
  VALRT_N  = SVID_VALERT_VCCIN_CPU0
  MP2  = PU_VR_PVCCIN_CPU0_FLT1_SMBALT_N
  AVSEN  = VSENSE_PVCCIN_CPU0_AVSP
  AVREF  = VSENSE_PVCCIN_CPU0_N
  AIREF1  = VR_PVCCIN_CPU0_AIREF1
  AISEN1  = ISENSE_PVCCIN_CPU0_PH1_IMON
  AIREF2  = VR_PVCCIN_CPU0_AIREF2
  AISEN2  = ISENSE_PVCCIN_CPU0_PH2_IMON
  AIREF3  = VR_PVCCIN_CPU0_AIREF3
  AISEN3  = ISENSE_PVCCIN_CPU0_PH3_IMON
  AIREF4  = VR_PVCCIN_CPU0_AIREF4
  AISEN4  = ISENSE_PVCCIN_CPU0_PH4_IMON
  AIREF5  = VR_PVCCIN_CPU0_AIREF5
  AISEN5  = ISENSE_PVCCIN_CPU0_PH5_IMON
  AIREF6  = NC
  AISEN6  = NC
  BVSEN  = VSENSE_PVSA_CPU0_BVSP
  BVREF  = VSENSE_PVSA_CPU0_N
  BIREF1  = VR_PVSA_CPU0_BIREF1
  BISEN1  = ISENSE_PVSA_CPU0_IMON
  MP3  = PU_VR_PVCCIN_CPU0_IMON
  MP4  = NC
  XADDR2  = VR_PVCCIN_CPU0_XADDR2
  BTSEN  = A_TSENSE_PVSA_CPU0
  ATSEN  = A_TSENSE_PVCCIN_CPU0
  XADDR1  = VR_PVCCIN_CPU0_XADDR1
  VINSEN  = VR_PVCCIN_CPU0_AVINSEN
  IINSEN  = NC
  VDD  = VR_PVCCIN_CPU0_VDD
  VD12  = VR_PVCCIN_CPU0_VD12
  THPAD  = GND

(kicad_pcb
	(version 20260206)
	(generator "pcbnew")
	(generator_version "10.0")
	(general
		(thickness 1.6)
		(legacy_teardrops no)
	)
	(paper "A4")
	(title_block
		(title "Wiwynn_Tioga_Pass_MB.brd")
		(comment 1 "Tioga Pass / footprint 1893 of 4770 (EU4D4), pads 18-34 of 49")
	)
	(layers
		(0 "F.Cu" signal "TOP")
		(4 "In1.Cu" signal "L2GND")
		(6 "In2.Cu" signal "L3")
		(8 "In3.Cu" signal "L4GND")
		(10 "In4.Cu" signal "L5")
		(12 "In5.Cu" signal "L6GND")
		(14 "In6.Cu" signal "L7VCC")
		(16 "In7.Cu" signal "L8VCC")
		(18 "In8.Cu" signal "L9GND")
		(20 "In9.Cu" signal "L10")
		(22 "In10.Cu" signal "L11GND")
		(24 "In11.Cu" signal "L12")
		(26 "In12.Cu" signal "L13GND")
		(2 "B.Cu" signal "BOTTOM")
		(9 "F.Adhes" user "F.Adhesive")
		(11 "B.Adhes" user "B.Adhesive")
		(13 "F.Paste" user "Package Geometry/Pastemask Top")
		(15 "B.Paste" user "Package Geometry/Pastemask Bottom")
		(5 "F.SilkS" user "Ref Des/Silkscreen Top")
		(7 "B.SilkS" user "Ref Des/Silkscreen Bottom")
		(1 "F.Mask" user "Board Geometry/Soldermask Top")
		(3 "B.Mask" user "Board Geometry/Soldermask Bottom")
		(17 "Dwgs.User" user "User.Drawings")
		(19 "Cmts.User" user "User.Comments")
		(21 "Eco1.User" user "User.Eco1")
		(23 "Eco2.User" user "User.Eco2")
		(25 "Edge.Cuts" user "Board Geometry/Outline")
		(27 "Margin" user)
		(31 "F.CrtYd" user "Package Geometry/Place Bound Top")
		(29 "B.CrtYd" user "Package Geometry/Place Bound Bottom")
		(35 "F.Fab" user "Ref Des/Assembly Top")
		(33 "B.Fab" user "Ref Des/Assembly Bottom")
	)
	(footprint ""
		(layer "F.Cu")
		(at 184.277 -69.85)
		(property "Reference" "EU4D4"
			(at -7.4422 -3.32613 0)
			(unlocked yes)
			(layer "F.SilkS")
			(effects
				(font
					(size 0.7874 0.5842)
					(thickness 0.1524)
				)
				(justify left)
			)
		)
		(property "Value" ""
			(at 0 0 0)
			(layer "F.Fab")
			(effects
				(font
					(size 1.27 1.27)
				)
			)
		)
		(duplicate_pad_numbers_are_jumpers no)
		(pad "18" smd custom
			(at -0.199898 2.8956)
			(size 0.0508 0.0508)
			(layers "F.Cu" "F.Mask" "F.Paste")
			(net "SVID_VDIO_PVCCIN_CPU0")
			(options
				(clearance outline)
				(anchor circle)
			)
			(primitives
				(gr_poly
					(pts
						(arc
							(start -0.1016 -0.254)
							(mid 0 -0.3556)
							(end 0.1016 -0.254)
						)
						(xy 0.1016 0.3556) (xy -0.1016 0.3556)
					)
					(width 0)
					(fill yes)
				)
			)
		)
		(pad "19" smd custom
			(at 0.199898 2.8956)
			(size 0.0508 0.0508)
			(layers "F.Cu" "F.Mask" "F.Paste")
			(net "SVID_VALERT_VCCIN_CPU0")
			(options
				(clearance outline)
				(anchor circle)
			)
			(primitives
				(gr_poly
					(pts
						(arc
							(start -0.1016 -0.254)
							(mid 0 -0.3556)
							(end 0.1016 -0.254)
						)
						(xy 0.1016 0.3556) (xy -0.1016 0.3556)
					)
					(width 0)
					(fill yes)
				)
			)
		)
		(pad "20" smd custom
			(at 0.599948 2.8956)
			(size 0.0508 0.0508)
			(layers "F.Cu" "F.Mask" "F.Paste")
			(net "PU_VR_PVCCIN_CPU0_FLT1_SMBALT_N")
			(options
				(clearance outline)
				(anchor circle)
			)
			(primitives
				(gr_poly
					(pts
						(arc
							(start -0.1016 -0.254)
							(mid 0 -0.3556)
							(end 0.1016 -0.254)
						)
						(xy 0.1016 0.3556) (xy -0.1016 0.3556)
					)
					(width 0)
					(fill yes)
				)
			)
		)
		(pad "21" smd custom
			(at 0.999998 2.8956)
			(size 0.0508 0.0508)
			(layers "F.Cu" "F.Mask" "F.Paste")
			(net "VSENSE_PVCCIN_CPU0_AVSP")
			(options
				(clearance outline)
				(anchor circle)
			)
			(primitives
				(gr_poly
					(pts
						(arc
							(start -0.1016 -0.254)
							(mid 0 -0.3556)
							(end 0.1016 -0.254)
						)
						(xy 0.1016 0.3556) (xy -0.1016 0.3556)
					)
					(width 0)
					(fill yes)
				)
			)
		)
		(pad "22" smd custom
			(at 1.400048 2.8956)
			(size 0.0508 0.0508)
			(layers "F.Cu" "F.Mask" "F.Paste")
			(net "VSENSE_PVCCIN_CPU0_N")
			(options
				(clearance outline)
				(anchor circle)
			)
			(primitives
				(gr_poly
					(pts
						(arc
							(start -0.1016 -0.254)
							(mid 0 -0.3556)
							(end 0.1016 -0.254)
						)
						(xy 0.1016 0.3556) (xy -0.1016 0.3556)
					)
					(width 0)
					(fill yes)
				)
			)
		)
		(pad "23" smd custom
			(at 1.800098 2.8956)
			(size 0.0508 0.0508)
			(layers "F.Cu" "F.Mask" "F.Paste")
			(net "VR_PVCCIN_CPU0_AIREF1")
			(options
				(clearance outline)
				(anchor circle)
			)
			(primitives
				(gr_poly
					(pts
						(arc
							(start -0.1016 -0.254)
							(mid 0 -0.3556)
							(end 0.1016 -0.254)
						)
						(xy 0.1016 0.3556) (xy -0.1016 0.3556)
					)
					(width 0)
					(fill yes)
				)
			)
		)
		(pad "24" smd custom
			(at 2.199894 2.8956)
			(size 0.0508 0.0508)
			(layers "F.Cu" "F.Mask" "F.Paste")
			(net "ISENSE_PVCCIN_CPU0_PH1_IMON")
			(options
				(clearance outline)
				(anchor circle)
			)
			(primitives
				(gr_poly
					(pts
						(arc
							(start -0.1016 -0.254)
							(mid 0 -0.3556)
							(end 0.1016 -0.254)
						)
						(xy 0.1016 0.3556) (xy -0.1016 0.3556)
					)
					(width 0)
					(fill yes)
				)
			)
		)
		(pad "25" smd custom
			(at 2.8956 2.199894)
			(size 0.0508 0.0508)
			(layers "F.Cu" "F.Mask" "F.Paste")
			(net "VR_PVCCIN_CPU0_AIREF2")
			(options
				(clearance outline)
				(anchor circle)
			)
			(primitives
				(gr_poly
					(pts
						(arc
							(start -0.254 0.1016)
							(mid -0.3556 0)
							(end -0.254 -0.1016)
						)
						(xy 0.3556 -0.1016) (xy 0.3556 0.1016)
					)
					(width 0)
					(fill yes)
				)
			)
		)
		(pad "26" smd custom
			(at 2.8956 1.800098)
			(size 0.0508 0.0508)
			(layers "F.Cu" "F.Mask" "F.Paste")
			(net "ISENSE_PVCCIN_CPU0_PH2_IMON")
			(options
				(clearance outline)
				(anchor circle)
			)
			(primitives
				(gr_poly
					(pts
						(arc
							(start -0.254 0.1016)
							(mid -0.3556 0)
							(end -0.254 -0.1016)
						)
						(xy 0.3556 -0.1016) (xy 0.3556 0.1016)
					)
					(width 0)
					(fill yes)
				)
			)
		)
		(pad "27" smd custom
			(at 2.8956 1.400048)
			(size 0.0508 0.0508)
			(layers "F.Cu" "F.Mask" "F.Paste")
			(net "VR_PVCCIN_CPU0_AIREF3")
			(options
				(clearance outline)
				(anchor circle)
			)
			(primitives
				(gr_poly
					(pts
						(arc
							(start -0.254 0.1016)
							(mid -0.3556 0)
							(end -0.254 -0.1016)
						)
						(xy 0.3556 -0.1016) (xy 0.3556 0.1016)
					)
					(width 0)
					(fill yes)
				)
			)
		)
		(pad "28" smd custom
			(at 2.8956 0.999998)
			(size 0.0508 0.0508)
			(layers "F.Cu" "F.Mask" "F.Paste")
			(net "ISENSE_PVCCIN_CPU0_PH3_IMON")
			(options
				(clearance outline)
				(anchor circle)
			)
			(primitives
				(gr_poly
					(pts
						(arc
							(start -0.254 0.1016)
							(mid -0.3556 0)
							(end -0.254 -0.1016)
						)
						(xy 0.3556 -0.1016) (xy 0.3556 0.1016)
					)
					(width 0)
					(fill yes)
				)
			)
		)
		(pad "29" smd custom
			(at 2.8956 0.599948)
			(size 0.0508 0.0508)
			(layers "F.Cu" "F.Mask" "F.Paste")
			(net "VR_PVCCIN_CPU0_AIREF4")
			(options
				(clearance outline)
				(anchor circle)
			)
			(primitives
				(gr_poly
					(pts
						(arc
							(start -0.254 0.1016)
							(mid -0.3556 0)
							(end -0.254 -0.1016)
						)
						(xy 0.3556 -0.1016) (xy 0.3556 0.1016)
					)
					(width 0)
					(fill yes)
				)
			)
		)
		(pad "30" smd custom
			(at 2.8956 0.199898)
			(size 0.0508 0.0508)
			(layers "F.Cu" "F.Mask" "F.Paste")
			(net "ISENSE_PVCCIN_CPU0_PH4_IMON")
			(options
				(clearance outline)
				(anchor circle)
			)
			(primitives
				(gr_poly
					(pts
						(arc
							(start -0.254 0.1016)
							(mid -0.3556 0)
							(end -0.254 -0.1016)
						)
						(xy 0.3556 -0.1016) (xy 0.3556 0.1016)
					)
					(width 0)
					(fill yes)
				)
			)
		)
		(pad "31" smd custom
			(at 2.8956 -0.199898)
			(size 0.0508 0.0508)
			(layers "F.Cu" "F.Mask" "F.Paste")
			(net "VR_PVCCIN_CPU0_AIREF5")
			(options
				(clearance outline)
				(anchor circle)
			)
			(primitives
				(gr_poly
					(pts
						(arc
							(start -0.254 0.1016)
							(mid -0.3556 0)
							(end -0.254 -0.1016)
						)
						(xy 0.3556 -0.1016) (xy 0.3556 0.1016)
					)
					(width 0)
					(fill yes)
				)
			)
		)
		(pad "32" smd custom
			(at 2.8956 -0.599948)
			(size 0.0508 0.0508)
			(layers "F.Cu" "F.Mask" "F.Paste")
			(net "ISENSE_PVCCIN_CPU0_PH5_IMON")
			(options
				(clearance outline)
				(anchor circle)
			)
			(primitives
				(gr_poly
					(pts
						(arc
							(start -0.254 0.1016)
							(mid -0.3556 0)
							(end -0.254 -0.1016)
						)
						(xy 0.3556 -0.1016) (xy 0.3556 0.1016)
					)
					(width 0)
					(fill yes)
				)
			)
		)
		(pad "33" smd custom
			(at 2.8956 -0.999998)
			(size 0.0508 0.0508)
			(layers "F.Cu" "F.Mask" "F.Paste")
			(net "Net_273")
			(options
				(clearance outline)
				(anchor circle)
			)
			(primitives
				(gr_poly
					(pts
						(arc
							(start -0.254 0.1016)
							(mid -0.3556 0)
							(end -0.254 -0.1016)
						)
						(xy 0.3556 -0.1016) (xy 0.3556 0.1016)
					)
					(width 0)
					(fill yes)
				)
			)
		)
		(pad "34" smd custom
			(at 2.8956 -1.400048)
			(size 0.0508 0.0508)
			(layers "F.Cu" "F.Mask" "F.Paste")
			(net "Net_290")
			(options
				(clearance outline)
				(anchor circle)
			)
			(primitives
				(gr_poly
					(pts
						(arc
							(start -0.254 0.1016)
							(mid -0.3556 0)
							(end -0.254 -0.1016)
						)
						(xy 0.3556 -0.1016) (xy 0.3556 0.1016)
					)
					(width 0)
					(fill yes)
				)
			)
		)
	)
)
